(kicad_pcb
	(version 20260206)
	(generator "pcbnew")
	(generator_version "10.0")
	(general
		(thickness 1.6)
		(legacy_teardrops no)
	)
	(paper "A4")
	(title_block
		(title "01162023_DA0F0TEBIF0_F0T_Expander_BD_F_brd_V02_OCP.brd")
		(comment 1 "Grand Teton / footprints 3054-3059 of 9728")
	)
	(layers
		(0 "F.Cu" signal "TOP")
		(4 "In1.Cu" signal "GND")
		(6 "In2.Cu" signal "VCC")
		(8 "In3.Cu" signal "VCC1")
		(10 "In4.Cu" signal "GND1")
		(12 "In5.Cu" signal "IN1")
		(14 "In6.Cu" signal "GND2")
		(16 "In7.Cu" signal "IN2")
		(18 "In8.Cu" signal "GND3")
		(20 "In9.Cu" signal "IN3")
		(22 "In10.Cu" signal "GND4")
		(24 "In11.Cu" signal "IN4")
		(26 "In12.Cu" signal "GND5")
		(28 "In13.Cu" signal "IN5")
		(30 "In14.Cu" signal "GND6")
		(32 "In15.Cu" signal "IN6")
		(34 "In16.Cu" signal "GND7")
		(2 "B.Cu" signal "BOTTOM")
		(9 "F.Adhes" user "F.Adhesive")
		(11 "B.Adhes" user "B.Adhesive")
		(13 "F.Paste" user "Package Geometry/Pastemask Top")
		(15 "B.Paste" user "Package Geometry/Pastemask Bottom")
		(5 "F.SilkS" user "Ref Des/Silkscreen Top")
		(7 "B.SilkS" user "Ref Des/Silkscreen Bottom")
		(1 "F.Mask" user "Board Geometry/Soldermask Top")
		(3 "B.Mask" user "Board Geometry/Soldermask Bottom")
		(17 "Dwgs.User" user "User.Drawings")
		(19 "Cmts.User" user "User.Comments")
		(21 "Eco1.User" user "User.Eco1")
		(23 "Eco2.User" user "User.Eco2")
		(25 "Edge.Cuts" user "Board Geometry/Outline")
		(27 "Margin" user)
		(31 "F.CrtYd" user "Package Geometry/Place Bound Top")
		(29 "B.CrtYd" user "Package Geometry/Place Bound Bottom")
		(35 "F.Fab" user "Ref Des/Assembly Top")
		(33 "B.Fab" user "Ref Des/Assembly Bottom")
	)
	(footprint ""
		(layer "F.Cu")
		(at 36.638484 -104.695498)
		(property "Reference" "C57"
			(at 0 0 0)
			(layer "F.SilkS")
			(hide yes)
			(effects
				(font
					(size 1.27 1.27)
				)
			)
		)
		(property "Value" ""
			(at 0 0 0)
			(layer "F.Fab")
			(effects
				(font
					(size 1.27 1.27)
				)
			)
		)
		(duplicate_pad_numbers_are_jumpers no)
		(fp_line
			(start -0.299974 -0.150114)
			(end 0.299974 -0.150114)
			(stroke
				(width 0.1)
				(type default)
			)
			(layer "F.Fab")
		)
		(fp_line
			(start -0.299974 0.150114)
			(end -0.299974 -0.150114)
			(stroke
				(width 0.1)
				(type default)
			)
			(layer "F.Fab")
		)
		(fp_line
			(start 0.299974 -0.150114)
			(end 0.299974 0.150114)
			(stroke
				(width 0.1)
				(type default)
			)
			(layer "F.Fab")
		)
		(fp_line
			(start 0.299974 0.150114)
			(end -0.299974 0.150114)
			(stroke
				(width 0.1)
				(type default)
			)
			(layer "F.Fab")
		)
		(pad "1" smd rect
			(at -0.2667 0)
			(size 0.3048 0.381)
			(layers "F.Cu" "F.Mask" "F.Paste")
			(net "P5E_PEX0_STN1_TX_DN<19>")
		)
		(pad "2" smd rect
			(at 0.2667 0)
			(size 0.3048 0.381)
			(layers "F.Cu" "F.Mask" "F.Paste")
			(net "P5E_PEX0_STN1_TX_C_DN<19>")
		)
	)
	(footprint ""
		(layer "F.Cu")
		(at 63.008764 -384.598926)
		(property "Reference" "R6300"
			(at 0 0 0)
			(layer "F.SilkS")
			(hide yes)
			(effects
				(font
					(size 1.27 1.27)
				)
			)
		)
		(property "Value" ""
			(at 0 0 0)
			(layer "F.Fab")
			(effects
				(font
					(size 1.27 1.27)
				)
			)
		)
		(duplicate_pad_numbers_are_jumpers no)
		(fp_line
			(start -0.7874 -0.4064)
			(end 0.7874 -0.4064)
			(stroke
				(width 0.1524)
				(type default)
			)
			(layer "F.SilkS")
		)
		(fp_line
			(start -0.7874 0.4064)
			(end -0.7874 -0.4064)
			(stroke
				(width 0.1524)
				(type default)
			)
			(layer "F.SilkS")
		)
		(fp_line
			(start 0.7874 -0.4064)
			(end 0.7874 0.4064)
			(stroke
				(width 0.1524)
				(type default)
			)
			(layer "F.SilkS")
		)
		(fp_line
			(start 0.7874 0.4064)
			(end -0.7874 0.4064)
			(stroke
				(width 0.1524)
				(type default)
			)
			(layer "F.SilkS")
		)
		(fp_line
			(start -0.67945 -0.305054)
			(end -0.12065 -0.305054)
			(stroke
				(width 0.1)
				(type default)
			)
			(layer "F.Fab")
		)
		(fp_line
			(start -0.67945 0.3048)
			(end -0.67945 -0.305054)
			(stroke
				(width 0.1)
				(type default)
			)
			(layer "F.Fab")
		)
		(fp_line
			(start -0.12065 -0.305054)
			(end -0.12065 -0.2794)
			(stroke
				(width 0.1)
				(type default)
			)
			(layer "F.Fab")
		)
		(fp_line
			(start -0.12065 -0.2794)
			(end 0.12065 -0.2794)
			(stroke
				(width 0.1)
				(type default)
			)
			(layer "F.Fab")
		)
		(fp_line
			(start -0.12065 0.2794)
			(end -0.12065 0.3048)
			(stroke
				(width 0.1)
				(type default)
			)
			(layer "F.Fab")
		)
		(fp_line
			(start -0.12065 0.3048)
			(end -0.67945 0.3048)
			(stroke
				(width 0.1)
				(type default)
			)
			(layer "F.Fab")
		)
		(fp_line
			(start 0.120396 0.2794)
			(end -0.12065 0.2794)
			(stroke
				(width 0.1)
				(type default)
			)
			(layer "F.Fab")
		)
		(fp_line
			(start 0.120396 0.3048)
			(end 0.120396 0.2794)
			(stroke
				(width 0.1)
				(type default)
			)
			(layer "F.Fab")
		)
		(fp_line
			(start 0.12065 -0.3048)
			(end 0.67945 -0.3048)
			(stroke
				(width 0.1)
				(type default)
			)
			(layer "F.Fab")
		)
		(fp_line
			(start 0.12065 -0.2794)
			(end 0.12065 -0.3048)
			(stroke
				(width 0.1)
				(type default)
			)
			(layer "F.Fab")
		)
		(fp_line
			(start 0.67945 -0.3048)
			(end 0.67945 0.3048)
			(stroke
				(width 0.1)
				(type default)
			)
			(layer "F.Fab")
		)
		(fp_line
			(start 0.67945 0.3048)
			(end 0.120396 0.3048)
			(stroke
				(width 0.1)
				(type default)
			)
			(layer "F.Fab")
		)
		(pad "1" smd circle
			(at -0.40005 0)
			(size 0 0)
			(layers "F.Cu" "F.Mask" "F.Paste")
			(net "RST_MB_PERST_1_N")
		)
		(pad "2" smd circle
			(at 0.40005 0)
			(size 0 0)
			(layers "F.Cu" "F.Mask" "F.Paste")
			(net "GND")
		)
	)
	(footprint ""
		(layer "F.Cu")
		(at 334.899 -234.061 90)
		(property "Reference" "R3523"
			(at 0 0 90)
			(layer "F.SilkS")
			(hide yes)
			(effects
				(font
					(size 1.27 1.27)
				)
			)
		)
		(property "Value" ""
			(at 0 0 90)
			(layer "F.Fab")
			(effects
				(font
					(size 1.27 1.27)
				)
			)
		)
		(duplicate_pad_numbers_are_jumpers no)
		(fp_line
			(start 0.7874 -0.4064)
			(end 0.7874 0.4064)
			(stroke
				(width 0.1524)
				(type default)
			)
			(layer "F.SilkS")
		)
		(fp_line
			(start -0.7874 -0.4064)
			(end 0.7874 -0.4064)
			(stroke
				(width 0.1524)
				(type default)
			)
			(layer "F.SilkS")
		)
		(fp_line
			(start 0.7874 0.4064)
			(end -0.7874 0.4064)
			(stroke
				(width 0.1524)
				(type default)
			)
			(layer "F.SilkS")
		)
		(fp_line
			(start -0.7874 0.4064)
			(end -0.7874 -0.4064)
			(stroke
				(width 0.1524)
				(type default)
			)
			(layer "F.SilkS")
		)
		(fp_line
			(start -0.12065 -0.305054)
			(end -0.12065 -0.2794)
			(stroke
				(width 0.1)
				(type default)
			)
			(layer "F.Fab")
		)
		(fp_line
			(start -0.67945 -0.305054)
			(end -0.12065 -0.305054)
			(stroke
				(width 0.1)
				(type default)
			)
			(layer "F.Fab")
		)
		(fp_line
			(start 0.67945 -0.3048)
			(end 0.67945 0.3048)
			(stroke
				(width 0.1)
				(type default)
			)
			(layer "F.Fab")
		)
		(fp_line
			(start 0.12065 -0.3048)
			(end 0.67945 -0.3048)
			(stroke
				(width 0.1)
				(type default)
			)
			(layer "F.Fab")
		)
		(fp_line
			(start 0.12065 -0.2794)
			(end 0.12065 -0.3048)
			(stroke
				(width 0.1)
				(type default)
			)
			(layer "F.Fab")
		)
		(fp_line
			(start -0.12065 -0.2794)
			(end 0.12065 -0.2794)
			(stroke
				(width 0.1)
				(type default)
			)
			(layer "F.Fab")
		)
		(fp_line
			(start 0.120396 0.2794)
			(end -0.12065 0.2794)
			(stroke
				(width 0.1)
				(type default)
			)
			(layer "F.Fab")
		)
		(fp_line
			(start -0.12065 0.2794)
			(end -0.12065 0.3048)
			(stroke
				(width 0.1)
				(type default)
			)
			(layer "F.Fab")
		)
		(fp_line
			(start 0.67945 0.3048)
			(end 0.120396 0.3048)
			(stroke
				(width 0.1)
				(type default)
			)
			(layer "F.Fab")
		)
		(fp_line
			(start 0.120396 0.3048)
			(end 0.120396 0.2794)
			(stroke
				(width 0.1)
				(type default)
			)
			(layer "F.Fab")
		)
		(fp_line
			(start -0.12065 0.3048)
			(end -0.67945 0.3048)
			(stroke
				(width 0.1)
				(type default)
			)
			(layer "F.Fab")
		)
		(fp_line
			(start -0.67945 0.3048)
			(end -0.67945 -0.305054)
			(stroke
				(width 0.1)
				(type default)
			)
			(layer "F.Fab")
		)
		(pad "1" smd circle
			(at -0.40005 0 90)
			(size 0 0)
			(layers "F.Cu" "F.Mask" "F.Paste")
			(net "SSD2_PWRDIS")
		)
		(pad "2" smd circle
			(at 0.40005 0 90)
			(size 0 0)
			(layers "F.Cu" "F.Mask" "F.Paste")
			(net "SSD2_PWRDIS_R")
		)
	)
	(footprint ""
		(layer "F.Cu")
		(at 441.366148 -306.074572 90)
		(property "Reference" "R4183"
			(at 0 0 90)
			(layer "F.SilkS")
			(hide yes)
			(effects
				(font
					(size 1.27 1.27)
				)
			)
		)
		(property "Value" ""
			(at 0 0 90)
			(layer "F.Fab")
			(effects
				(font
					(size 1.27 1.27)
				)
			)
		)
		(duplicate_pad_numbers_are_jumpers no)
		(fp_line
			(start 0.7874 -0.4064)
			(end 0.7874 0.4064)
			(stroke
				(width 0.1524)
				(type default)
			)
			(layer "F.SilkS")
		)
		(fp_line
			(start -0.7874 -0.4064)
			(end 0.7874 -0.4064)
			(stroke
				(width 0.1524)
				(type default)
			)
			(layer "F.SilkS")
		)
		(fp_line
			(start 0.7874 0.4064)
			(end -0.7874 0.4064)
			(stroke
				(width 0.1524)
				(type default)
			)
			(layer "F.SilkS")
		)
		(fp_line
			(start -0.7874 0.4064)
			(end -0.7874 -0.4064)
			(stroke
				(width 0.1524)
				(type default)
			)
			(layer "F.SilkS")
		)
		(fp_line
			(start -0.12065 -0.305054)
			(end -0.12065 -0.2794)
			(stroke
				(width 0.1)
				(type default)
			)
			(layer "F.Fab")
		)
		(fp_line
			(start -0.67945 -0.305054)
			(end -0.12065 -0.305054)
			(stroke
				(width 0.1)
				(type default)
			)
			(layer "F.Fab")
		)
		(fp_line
			(start 0.67945 -0.3048)
			(end 0.67945 0.3048)
			(stroke
				(width 0.1)
				(type default)
			)
			(layer "F.Fab")
		)
		(fp_line
			(start 0.12065 -0.3048)
			(end 0.67945 -0.3048)
			(stroke
				(width 0.1)
				(type default)
			)
			(layer "F.Fab")
		)
		(fp_line
			(start 0.12065 -0.2794)
			(end 0.12065 -0.3048)
			(stroke
				(width 0.1)
				(type default)
			)
			(layer "F.Fab")
		)
		(fp_line
			(start -0.12065 -0.2794)
			(end 0.12065 -0.2794)
			(stroke
				(width 0.1)
				(type default)
			)
			(layer "F.Fab")
		)
		(fp_line
			(start 0.120396 0.2794)
			(end -0.12065 0.2794)
			(stroke
				(width 0.1)
				(type default)
			)
			(layer "F.Fab")
		)
		(fp_line
			(start -0.12065 0.2794)
			(end -0.12065 0.3048)
			(stroke
				(width 0.1)
				(type default)
			)
			(layer "F.Fab")
		)
		(fp_line
			(start 0.67945 0.3048)
			(end 0.120396 0.3048)
			(stroke
				(width 0.1)
				(type default)
			)
			(layer "F.Fab")
		)
		(fp_line
			(start 0.120396 0.3048)
			(end 0.120396 0.2794)
			(stroke
				(width 0.1)
				(type default)
			)
			(layer "F.Fab")
		)
		(fp_line
			(start -0.12065 0.3048)
			(end -0.67945 0.3048)
			(stroke
				(width 0.1)
				(type default)
			)
			(layer "F.Fab")
		)
		(fp_line
			(start -0.67945 0.3048)
			(end -0.67945 -0.305054)
			(stroke
				(width 0.1)
				(type default)
			)
			(layer "F.Fab")
		)
		(pad "1" smd circle
			(at -0.40005 0 90)
			(size 0 0)
			(layers "F.Cu" "F.Mask" "F.Paste")
			(net "PEX3_EXT_GPIO_LATCH_N")
		)
		(pad "2" smd circle
			(at 0.40005 0 90)
			(size 0 0)
			(layers "F.Cu" "F.Mask" "F.Paste")
			(net "P1V8_PEX")
		)
	)
	(footprint ""
		(layer "F.Cu")
		(at 77.107542 -81.09966)
		(property "Reference" "Q2"
			(at -1.263142 1.75133 0)
			(unlocked yes)
			(layer "F.SilkS")
			(effects
				(font
					(size 0.7874 0.5842)
					(thickness 0.1524)
				)
				(justify left)
			)
		)
		(property "Value" ""
			(at 0 0 0)
			(layer "F.Fab")
			(effects
				(font
					(size 1.27 1.27)
				)
			)
		)
		(duplicate_pad_numbers_are_jumpers no)
		(fp_line
			(start -1.38176 -1.100074)
			(end -1.38176 1.100074)
			(stroke
				(width 0.1524)
				(type default)
			)
			(layer "F.SilkS")
		)
		(fp_line
			(start -1.38176 1.100074)
			(end 1.38176 1.100074)
			(stroke
				(width 0.1524)
				(type default)
			)
			(layer "F.SilkS")
		)
		(fp_line
			(start -0.592074 -1.100074)
			(end -1.38176 -1.100074)
			(stroke
				(width 0.1524)
				(type default)
			)
			(layer "F.SilkS")
		)
		(fp_line
			(start 0 -0.508)
			(end -0.592074 -1.100074)
			(stroke
				(width 0.1524)
				(type default)
			)
			(layer "F.SilkS")
		)
		(fp_line
			(start 0.592074 -1.100074)
			(end 0 -0.508)
			(stroke
				(width 0.1524)
				(type default)
			)
			(layer "F.SilkS")
		)
		(fp_line
			(start 1.38176 -1.100074)
			(end 0.592074 -1.100074)
			(stroke
				(width 0.1524)
				(type default)
			)
			(layer "F.SilkS")
		)
		(fp_line
			(start 1.38176 1.100074)
			(end 1.38176 -1.100074)
			(stroke
				(width 0.1524)
				(type default)
			)
			(layer "F.SilkS")
		)
		(fp_poly
			(pts
				(xy -1.9431 -0.870204) (xy -1.50241 -0.649986) (xy -1.9431 -0.429768)
			)
			(stroke
				(width 0)
				(type default)
			)
			(fill yes)
			(layer "F.SilkS")
		)
		(fp_line
			(start -0.674878 -1.100074)
			(end -0.674878 1.100074)
			(stroke
				(width 0.1)
				(type default)
			)
			(layer "F.Fab")
		)
		(fp_line
			(start -0.674878 1.100074)
			(end 0.674878 1.100074)
			(stroke
				(width 0.1)
				(type default)
			)
			(layer "F.Fab")
		)
		(fp_line
			(start 0.674878 -1.100074)
			(end -0.674878 -1.100074)
			(stroke
				(width 0.1)
				(type default)
			)
			(layer "F.Fab")
		)
		(fp_line
			(start 0.674878 1.100074)
			(end 0.674878 -1.100074)
			(stroke
				(width 0.1)
				(type default)
			)
			(layer "F.Fab")
		)
		(fp_poly
			(pts
				(xy -1.9431 -0.870204) (xy -1.50241 -0.649986) (xy -1.9431 -0.429768)
			)
			(stroke
				(width 0)
				(type default)
			)
			(fill yes)
			(layer "F.Fab")
		)
		(pad "1" smd rect
			(at -0.94996 -0.649986 270)
			(size 0.4318 0.6096)
			(layers "F.Cu" "F.Mask" "F.Paste")
			(net "GND")
		)
		(pad "2" smd rect
			(at -0.94996 0 270)
			(size 0.4318 0.6096)
			(layers "F.Cu" "F.Mask" "F.Paste")
			(net "HP_NIC1_HSC_PWRGD_N")
		)
		(pad "3" smd rect
			(at -0.94996 0.649986 270)
			(size 0.4318 0.6096)
			(layers "F.Cu" "F.Mask" "F.Paste")
			(net "HP_NIC1_HSC_PWRGD_N")
		)
		(pad "4" smd rect
			(at 0.94996 0.649986 270)
			(size 0.4318 0.6096)
			(layers "F.Cu" "F.Mask" "F.Paste")
			(net "GND")
		)
		(pad "5" smd rect
			(at 0.94996 0 270)
			(size 0.4318 0.6096)
			(layers "F.Cu" "F.Mask" "F.Paste")
			(net "PWRGD_P12V_NIC1_R")
		)
		(pad "6" smd rect
			(at 0.94996 -0.649986 270)
			(size 0.4318 0.6096)
			(layers "F.Cu" "F.Mask" "F.Paste")
			(net "HP_NIC1_PWRGD_R")
		)
	)
	(footprint ""
		(layer "F.Cu")
		(at 420.8145 -66.32194 90)
		(property "Reference" "R6020"
			(at 0 0 90)
			(layer "F.SilkS")
			(hide yes)
			(effects
				(font
					(size 1.27 1.27)
				)
			)
		)
		(property "Value" ""
			(at 0 0 90)
			(layer "F.Fab")
			(effects
				(font
					(size 1.27 1.27)
				)
			)
		)
		(duplicate_pad_numbers_are_jumpers no)
		(fp_line
			(start 0.7874 -0.4064)
			(end 0.7874 0.4064)
			(stroke
				(width 0.1524)
				(type default)
			)
			(layer "F.SilkS")
		)
		(fp_line
			(start -0.7874 -0.4064)
			(end 0.7874 -0.4064)
			(stroke
				(width 0.1524)
				(type default)
			)
			(layer "F.SilkS")
		)
		(fp_line
			(start 0.7874 0.4064)
			(end -0.7874 0.4064)
			(stroke
				(width 0.1524)
				(type default)
			)
			(layer "F.SilkS")
		)
		(fp_line
			(start -0.7874 0.4064)
			(end -0.7874 -0.4064)
			(stroke
				(width 0.1524)
				(type default)
			)
			(layer "F.SilkS")
		)
		(fp_line
			(start -0.12065 -0.305054)
			(end -0.12065 -0.2794)
			(stroke
				(width 0.1)
				(type default)
			)
			(layer "F.Fab")
		)
		(fp_line
			(start -0.67945 -0.305054)
			(end -0.12065 -0.305054)
			(stroke
				(width 0.1)
				(type default)
			)
			(layer "F.Fab")
		)
		(fp_line
			(start 0.67945 -0.3048)
			(end 0.67945 0.3048)
			(stroke
				(width 0.1)
				(type default)
			)
			(layer "F.Fab")
		)
		(fp_line
			(start 0.12065 -0.3048)
			(end 0.67945 -0.3048)
			(stroke
				(width 0.1)
				(type default)
			)
			(layer "F.Fab")
		)
		(fp_line
			(start 0.12065 -0.2794)
			(end 0.12065 -0.3048)
			(stroke
				(width 0.1)
				(type default)
			)
			(layer "F.Fab")
		)
		(fp_line
			(start -0.12065 -0.2794)
			(end 0.12065 -0.2794)
			(stroke
				(width 0.1)
				(type default)
			)
			(layer "F.Fab")
		)
		(fp_line
			(start 0.120396 0.2794)
			(end -0.12065 0.2794)
			(stroke
				(width 0.1)
				(type default)
			)
			(layer "F.Fab")
		)
		(fp_line
			(start -0.12065 0.2794)
			(end -0.12065 0.3048)
			(stroke
				(width 0.1)
				(type default)
			)
			(layer "F.Fab")
		)
		(fp_line
			(start 0.67945 0.3048)
			(end 0.120396 0.3048)
			(stroke
				(width 0.1)
				(type default)
			)
			(layer "F.Fab")
		)
		(fp_line
			(start 0.120396 0.3048)
			(end 0.120396 0.2794)
			(stroke
				(width 0.1)
				(type default)
			)
			(layer "F.Fab")
		)
		(fp_line
			(start -0.12065 0.3048)
			(end -0.67945 0.3048)
			(stroke
				(width 0.1)
				(type default)
			)
			(layer "F.Fab")
		)
		(fp_line
			(start -0.67945 0.3048)
			(end -0.67945 -0.305054)
			(stroke
				(width 0.1)
				(type default)
			)
			(layer "F.Fab")
		)
		(pad "1" smd circle
			(at -0.40005 0 90)
			(size 0 0)
			(layers "F.Cu" "F.Mask" "F.Paste")
			(net "SSD14_PWR_EN_R")
		)
		(pad "2" smd circle
			(at 0.40005 0 90)
			(size 0 0)
			(layers "F.Cu" "F.Mask" "F.Paste")
			(net "P12V_SSD14_CO_EN")
		)
	)
)
